# T6G (Grand Teton) — schematic netlist excerpt (pin names and nets, part order shuffled) for the footprints in the layout excerpt that follows; sources: Cadence DE-HDL packaged netlist, KiCad conversion of 04192023_DAF0TMB3IC0_F0TG_MB_C_brd_V02_OCP.brd

R6162  Q_RES  0 5% CHIP  pkg 0402LF  page 112 : A = FM_P2E_EN2_N ; B = CLK_GEN2_GPU_FPGA_OE_OR_N
C835  Q_CAP_DIFFBUS  DIFF BUS_0.22UF 6.3V 20% X6S  pkg C0201  page 65 : \1\ = P5E_CPU1_P0_TX_C_DP<1> ; \2\ = P5E_CPU1_P0_TX_DP<1>
PR203  Q_RES  5.6 1% CHIP  pkg 0402LF  page 213 : A = SW_PVDDCR_CPU0_P1_BOOT5 ; B = SW_PVDDCR_CPU0_P1_BOOT5_RC

(kicad_pcb
	(version 20260206)
	(generator "pcbnew")
	(generator_version "10.0")
	(general
		(thickness 1.6)
		(legacy_teardrops no)
	)
	(paper "A4")
	(title_block
		(title "04192023_DAF0TMB3IC0_F0TG_MB_C_brd_V02_OCP.brd")
		(comment 1 "Grand Teton / footprints 119-121 of 8354")
	)
	(layers
		(0 "F.Cu" signal "TOP")
		(4 "In1.Cu" signal "GND")
		(6 "In2.Cu" signal "IN1")
		(8 "In3.Cu" signal "GND1")
		(10 "In4.Cu" signal "IN2")
		(12 "In5.Cu" signal "GND2")
		(14 "In6.Cu" signal "IN3")
		(16 "In7.Cu" signal "GND3")
		(18 "In8.Cu" signal "VCC")
		(20 "In9.Cu" signal "VCC1")
		(22 "In10.Cu" signal "GND4")
		(24 "In11.Cu" signal "IN4")
		(26 "In12.Cu" signal "GND5")
		(28 "In13.Cu" signal "IN5")
		(30 "In14.Cu" signal "GND6")
		(32 "In15.Cu" signal "IN6")
		(34 "In16.Cu" signal "GND7")
		(2 "B.Cu" signal "BOTTOM")
		(9 "F.Adhes" user "F.Adhesive")
		(11 "B.Adhes" user "B.Adhesive")
		(13 "F.Paste" user "Package Geometry/Pastemask Top")
		(15 "B.Paste" user "Package Geometry/Pastemask Bottom")
		(5 "F.SilkS" user "Ref Des/Silkscreen Top")
		(7 "B.SilkS" user "Ref Des/Silkscreen Bottom")
		(1 "F.Mask" user "Board Geometry/Soldermask Top")
		(3 "B.Mask" user "Board Geometry/Soldermask Bottom")
		(17 "Dwgs.User" user "User.Drawings")
		(19 "Cmts.User" user "User.Comments")
		(21 "Eco1.User" user "User.Eco1")
		(23 "Eco2.User" user "User.Eco2")
		(25 "Edge.Cuts" user "Board Geometry/Outline")
		(27 "Margin" user)
		(31 "F.CrtYd" user "Package Geometry/Place Bound Top")
		(29 "B.CrtYd" user "Package Geometry/Place Bound Bottom")
		(35 "F.Fab" user "Ref Des/Assembly Top")
		(33 "B.Fab" user "Ref Des/Assembly Bottom")
	)
	(footprint ""
		(layer "F.Cu")
		(at 11.843258 -427.13783 180)
		(property "Reference" "R6162"
			(at 0 0 180)
			(layer "F.SilkS")
			(hide yes)
			(effects
				(font
					(size 1.27 1.27)
				)
			)
		)
		(property "Value" ""
			(at 0 0 180)
			(layer "F.Fab")
			(effects
				(font
					(size 1.27 1.27)
				)
			)
		)
		(duplicate_pad_numbers_are_jumpers no)
		(fp_line
			(start 0.7874 0.4064)
			(end -0.7874 0.4064)
			(stroke
				(width 0.1524)
				(type default)
			)
			(layer "F.SilkS")
		)
		(fp_line
			(start 0.7874 -0.4064)
			(end 0.7874 0.4064)
			(stroke
				(width 0.1524)
				(type default)
			)
			(layer "F.SilkS")
		)
		(fp_line
			(start -0.7874 0.4064)
			(end -0.7874 -0.4064)
			(stroke
				(width 0.1524)
				(type default)
			)
			(layer "F.SilkS")
		)
		(fp_line
			(start -0.7874 -0.4064)
			(end 0.7874 -0.4064)
			(stroke
				(width 0.1524)
				(type default)
			)
			(layer "F.SilkS")
		)
		(fp_line
			(start 0.67945 0.3048)
			(end 0.120396 0.3048)
			(stroke
				(width 0.1)
				(type default)
			)
			(layer "F.Fab")
		)
		(fp_line
			(start 0.67945 -0.3048)
			(end 0.67945 0.3048)
			(stroke
				(width 0.1)
				(type default)
			)
			(layer "F.Fab")
		)
		(fp_line
			(start 0.12065 -0.2794)
			(end 0.12065 -0.3048)
			(stroke
				(width 0.1)
				(type default)
			)
			(layer "F.Fab")
		)
		(fp_line
			(start 0.12065 -0.3048)
			(end 0.67945 -0.3048)
			(stroke
				(width 0.1)
				(type default)
			)
			(layer "F.Fab")
		)
		(fp_line
			(start 0.120396 0.3048)
			(end 0.120396 0.2794)
			(stroke
				(width 0.1)
				(type default)
			)
			(layer "F.Fab")
		)
		(fp_line
			(start 0.120396 0.2794)
			(end -0.12065 0.2794)
			(stroke
				(width 0.1)
				(type default)
			)
			(layer "F.Fab")
		)
		(fp_line
			(start -0.12065 0.3048)
			(end -0.67945 0.3048)
			(stroke
				(width 0.1)
				(type default)
			)
			(layer "F.Fab")
		)
		(fp_line
			(start -0.12065 0.2794)
			(end -0.12065 0.3048)
			(stroke
				(width 0.1)
				(type default)
			)
			(layer "F.Fab")
		)
		(fp_line
			(start -0.12065 -0.2794)
			(end 0.12065 -0.2794)
			(stroke
				(width 0.1)
				(type default)
			)
			(layer "F.Fab")
		)
		(fp_line
			(start -0.12065 -0.305054)
			(end -0.12065 -0.2794)
			(stroke
				(width 0.1)
				(type default)
			)
			(layer "F.Fab")
		)
		(fp_line
			(start -0.67945 0.3048)
			(end -0.67945 -0.305054)
			(stroke
				(width 0.1)
				(type default)
			)
			(layer "F.Fab")
		)
		(fp_line
			(start -0.67945 -0.305054)
			(end -0.12065 -0.305054)
			(stroke
				(width 0.1)
				(type default)
			)
			(layer "F.Fab")
		)
		(pad "1" smd circle
			(at -0.40005 0 180)
			(size 0 0)
			(layers "F.Cu" "F.Mask" "F.Paste")
			(net "FM_P2E_EN2_N")
		)
		(pad "2" smd circle
			(at 0.40005 0 180)
			(size 0 0)
			(layers "F.Cu" "F.Mask" "F.Paste")
			(net "CLK_GEN2_GPU_FPGA_OE_OR_N")
		)
	)
	(footprint ""
		(layer "F.Cu")
		(at 73.201784 -172.974 -90)
		(property "Reference" "PR203"
			(at 0 0 270)
			(layer "F.SilkS")
			(hide yes)
			(effects
				(font
					(size 1.27 1.27)
				)
			)
		)
		(property "Value" ""
			(at 0 0 270)
			(layer "F.Fab")
			(effects
				(font
					(size 1.27 1.27)
				)
			)
		)
		(duplicate_pad_numbers_are_jumpers no)
		(fp_line
			(start -0.7874 0.4064)
			(end -0.7874 -0.4064)
			(stroke
				(width 0.1524)
				(type default)
			)
			(layer "F.SilkS")
		)
		(fp_line
			(start 0.7874 0.4064)
			(end -0.7874 0.4064)
			(stroke
				(width 0.1524)
				(type default)
			)
			(layer "F.SilkS")
		)
		(fp_line
			(start -0.7874 -0.4064)
			(end 0.7874 -0.4064)
			(stroke
				(width 0.1524)
				(type default)
			)
			(layer "F.SilkS")
		)
		(fp_line
			(start 0.7874 -0.4064)
			(end 0.7874 0.4064)
			(stroke
				(width 0.1524)
				(type default)
			)
			(layer "F.SilkS")
		)
		(fp_line
			(start -0.67945 0.3048)
			(end -0.67945 -0.305054)
			(stroke
				(width 0.1)
				(type default)
			)
			(layer "F.Fab")
		)
		(fp_line
			(start -0.12065 0.3048)
			(end -0.67945 0.3048)
			(stroke
				(width 0.1)
				(type default)
			)
			(layer "F.Fab")
		)
		(fp_line
			(start 0.120396 0.3048)
			(end 0.120396 0.2794)
			(stroke
				(width 0.1)
				(type default)
			)
			(layer "F.Fab")
		)
		(fp_line
			(start 0.67945 0.3048)
			(end 0.120396 0.3048)
			(stroke
				(width 0.1)
				(type default)
			)
			(layer "F.Fab")
		)
		(fp_line
			(start -0.12065 0.2794)
			(end -0.12065 0.3048)
			(stroke
				(width 0.1)
				(type default)
			)
			(layer "F.Fab")
		)
		(fp_line
			(start 0.120396 0.2794)
			(end -0.12065 0.2794)
			(stroke
				(width 0.1)
				(type default)
			)
			(layer "F.Fab")
		)
		(fp_line
			(start -0.12065 -0.2794)
			(end 0.12065 -0.2794)
			(stroke
				(width 0.1)
				(type default)
			)
			(layer "F.Fab")
		)
		(fp_line
			(start 0.12065 -0.2794)
			(end 0.12065 -0.3048)
			(stroke
				(width 0.1)
				(type default)
			)
			(layer "F.Fab")
		)
		(fp_line
			(start 0.12065 -0.3048)
			(end 0.67945 -0.3048)
			(stroke
				(width 0.1)
				(type default)
			)
			(layer "F.Fab")
		)
		(fp_line
			(start 0.67945 -0.3048)
			(end 0.67945 0.3048)
			(stroke
				(width 0.1)
				(type default)
			)
			(layer "F.Fab")
		)
		(fp_line
			(start -0.67945 -0.305054)
			(end -0.12065 -0.305054)
			(stroke
				(width 0.1)
				(type default)
			)
			(layer "F.Fab")
		)
		(fp_line
			(start -0.12065 -0.305054)
			(end -0.12065 -0.2794)
			(stroke
				(width 0.1)
				(type default)
			)
			(layer "F.Fab")
		)
		(pad "1" smd circle
			(at -0.40005 0 270)
			(size 0 0)
			(layers "F.Cu" "F.Mask" "F.Paste")
			(net "SW_PVDDCR_CPU0_P1_BOOT5")
		)
		(pad "2" smd circle
			(at 0.40005 0 270)
			(size 0 0)
			(layers "F.Cu" "F.Mask" "F.Paste")
			(net "SW_PVDDCR_CPU0_P1_BOOT5_RC")
		)
	)
	(footprint ""
		(layer "F.Cu")
		(at 42.967402 -375.94286 180)
		(property "Reference" "C835"
			(at 0 0 180)
			(layer "F.SilkS")
			(hide yes)
			(effects
				(font
					(size 1.27 1.27)
				)
			)
		)
		(property "Value" ""
			(at 0 0 180)
			(layer "F.Fab")
			(effects
				(font
					(size 1.27 1.27)
				)
			)
		)
		(duplicate_pad_numbers_are_jumpers no)
		(fp_line
			(start 0.299974 0.150114)
			(end -0.299974 0.150114)
			(stroke
				(width 0.1)
				(type default)
			)
			(layer "F.Fab")
		)
		(fp_line
			(start 0.299974 -0.150114)
			(end 0.299974 0.150114)
			(stroke
				(width 0.1)
				(type default)
			)
			(layer "F.Fab")
		)
		(fp_line
			(start -0.299974 0.150114)
			(end -0.299974 -0.150114)
			(stroke
				(width 0.1)
				(type default)
			)
			(layer "F.Fab")
		)
		(fp_line
			(start -0.299974 -0.150114)
			(end 0.299974 -0.150114)
			(stroke
				(width 0.1)
				(type default)
			)
			(layer "F.Fab")
		)
		(pad "1" smd rect
			(at -0.2667 0 180)
			(size 0.3048 0.381)
			(layers "F.Cu" "F.Mask" "F.Paste")
			(net "P5E_CPU1_P0_TX_C_DP<1>")
		)
		(pad "2" smd rect
			(at 0.2667 0 180)
			(size 0.3048 0.381)
			(layers "F.Cu" "F.Mask" "F.Paste")
			(net "P5E_CPU1_P0_TX_DP<1>")
		)
	)
)
